(kicad_sch
	(version 20250114)
	(generator "eeschema")
	(generator_version "9.0")
	(paper "A3")
	(title_block
		(title "PolarFire SoM")
		(date "2025-07-22")
		(rev "1.1.4")
		(company "Antmicro Ltd")
		(comment 1 "www.antmicro.com")
	)
	(bus_alias "SGMII"
		(members "TX0_P" "TX0_N" "RX0_P" "RX0_N")
	)
	(text "PolarFire main clock"
		(exclude_from_sim no)
		(at 46.99 227.33 0)
		(effects
			(font
				(size 4 4)
				(thickness 0.8)
				(bold yes)
			)
			(justify left bottom)
		)
	)
	(text "PolarFire Bank 0\nHSIO"
		(exclude_from_sim no)
		(at 16.51 29.21 0)
		(effects
			(font
				(size 4 4)
				(thickness 0.8)
				(bold yes)
			)
			(justify left bottom)
		)
	)
	(junction
		(at 49.53 248.92)
		(diameter 0)
		(color 0 0 0 0)
	)
	(junction
		(at 58.42 242.57)
		(diameter 0)
		(color 0 0 0 0)
	)
	(junction
		(at 49.53 241.3)
		(diameter 0)
		(color 0 0 0 0)
	)
	(no_connect
		(at 269.24 82.55)
	)
	(no_connect
		(at 177.8 92.71)
	)
	(no_connect
		(at 269.24 80.01)
	)
	(no_connect
		(at 269.24 148.59)
	)
	(no_connect
		(at 177.8 148.59)
	)
	(no_connect
		(at 269.24 105.41)
	)
	(no_connect
		(at 177.8 146.05)
	)
	(no_connect
		(at 177.8 151.13)
	)
	(no_connect
		(at 269.24 128.27)
	)
	(no_connect
		(at 269.24 130.81)
	)
	(no_connect
		(at 269.24 110.49)
	)
	(no_connect
		(at 269.24 92.71)
	)
	(no_connect
		(at 269.24 95.25)
	)
	(no_connect
		(at 269.24 85.09)
	)
	(no_connect
		(at 269.24 100.33)
	)
	(no_connect
		(at 269.24 87.63)
	)
	(no_connect
		(at 269.24 97.79)
	)
	(no_connect
		(at 269.24 90.17)
	)
	(no_connect
		(at 269.24 77.47)
	)
	(no_connect
		(at 269.24 138.43)
	)
	(no_connect
		(at 269.24 115.57)
	)
	(no_connect
		(at 269.24 135.89)
	)
	(no_connect
		(at 269.24 113.03)
	)
	(no_connect
		(at 269.24 118.11)
	)
	(no_connect
		(at 269.24 102.87)
	)
	(no_connect
		(at 269.24 151.13)
	)
	(no_connect
		(at 269.24 143.51)
	)
	(no_connect
		(at 269.24 140.97)
	)
	(no_connect
		(at 269.24 125.73)
	)
	(no_connect
		(at 269.24 123.19)
	)
	(no_connect
		(at 269.24 120.65)
	)
	(no_connect
		(at 269.24 146.05)
	)
	(no_connect
		(at 269.24 107.95)
	)
	(bus_entry
		(at 124.46 128.27)
		(size 2.54 2.54)
		(stroke
			(width 0)
			(type default)
		)
	)
	(bus_entry
		(at 149.86 116.84)
		(size 1.27 1.27)
		(stroke
			(width 0)
			(type default)
		)
	)
	(bus_entry
		(at 149.86 134.62)
		(size 1.27 1.27)
		(stroke
			(width 0)
			(type default)
		)
	)
	(bus_entry
		(at 149.86 111.76)
		(size 1.27 1.27)
		(stroke
			(width 0)
			(type default)
		)
	)
	(bus_entry
		(at 149.86 78.74)
		(size 1.27 1.27)
		(stroke
			(width 0)
			(type default)
		)
	)
	(bus_entry
		(at 124.46 82.55)
		(size 2.54 2.54)
		(stroke
			(width 0)
			(type default)
		)
	)
	(bus_entry
		(at 149.86 142.24)
		(size 1.27 1.27)
		(stroke
			(width 0)
			(type default)
		)
	)
	(bus_entry
		(at 124.46 95.25)
		(size 2.54 2.54)
		(stroke
			(width 0)
			(type default)
		)
	)
	(bus_entry
		(at 149.86 114.3)
		(size 1.27 1.27)
		(stroke
			(width 0)
			(type default)
		)
	)
	(bus_entry
		(at 124.46 105.41)
		(size 2.54 2.54)
		(stroke
			(width 0)
			(type default)
		)
	)
	(bus_entry
		(at 149.86 124.46)
		(size 1.27 1.27)
		(stroke
			(width 0)
			(type default)
		)
	)
	(bus_entry
		(at 149.86 76.2)
		(size 1.27 1.27)
		(stroke
			(width 0)
			(type default)
		)
	)
	(bus_entry
		(at 149.86 132.08)
		(size 1.27 1.27)
		(stroke
			(width 0)
			(type default)
		)
	)
	(bus_entry
		(at 124.46 135.89)
		(size 2.54 2.54)
		(stroke
			(width 0)
			(type default)
		)
	)
	(bus_entry
		(at 124.46 102.87)
		(size 2.54 2.54)
		(stroke
			(width 0)
			(type default)
		)
	)
	(bus_entry
		(at 124.46 87.63)
		(size 2.54 2.54)
		(stroke
			(width 0)
			(type default)
		)
	)
	(bus_entry
		(at 124.46 92.71)
		(size 2.54 2.54)
		(stroke
			(width 0)
			(type default)
		)
	)
	(bus_entry
		(at 124.46 100.33)
		(size 2.54 2.54)
		(stroke
			(width 0)
			(type default)
		)
	)
	(bus_entry
		(at 124.46 120.65)
		(size 2.54 2.54)
		(stroke
			(width 0)
			(type default)
		)
	)
	(bus_entry
		(at 149.86 109.22)
		(size 1.27 1.27)
		(stroke
			(width 0)
			(type default)
		)
	)
	(bus_entry
		(at 124.46 138.43)
		(size 2.54 2.54)
		(stroke
			(width 0)
			(type default)
		)
	)
	(bus_entry
		(at 149.86 127)
		(size 1.27 1.27)
		(stroke
			(width 0)
			(type default)
		)
	)
	(bus_entry
		(at 149.86 119.38)
		(size 1.27 1.27)
		(stroke
			(width 0)
			(type default)
		)
	)
	(bus_entry
		(at 149.86 81.28)
		(size 1.27 1.27)
		(stroke
			(width 0)
			(type default)
		)
	)
	(bus_entry
		(at 124.46 97.79)
		(size 2.54 2.54)
		(stroke
			(width 0)
			(type default)
		)
	)
	(bus_entry
		(at 124.46 85.09)
		(size 2.54 2.54)
		(stroke
			(width 0)
			(type default)
		)
	)
	(bus
		(pts
			(xy 124.46 81.28) (xy 123.19 80.01)
		)
		(stroke
			(width 0)
			(type default)
		)
	)
	(wire
		(pts
			(xy 151.13 82.55) (xy 177.8 82.55)
		)
		(stroke
			(width 0)
			(type default)
		)
	)
	(wire
		(pts
			(xy 127 138.43) (xy 177.8 138.43)
		)
		(stroke
			(width 0)
			(type default)
		)
	)
	(wire
		(pts
			(xy 151.13 125.73) (xy 177.8 125.73)
		)
		(stroke
			(width 0)
			(type default)
		)
	)
	(wire
		(pts
			(xy 151.13 118.11) (xy 177.8 118.11)
		)
		(stroke
			(width 0)
			(type default)
		)
	)
	(wire
		(pts
			(xy 127 107.95) (xy 177.8 107.95)
		)
		(stroke
			(width 0)
			(type default)
		)
	)
	(bus
		(pts
			(xy 124.46 95.25) (xy 124.46 97.79)
		)
		(stroke
			(width 0)
			(type default)
		)
	)
	(wire
		(pts
			(xy 127 140.97) (xy 177.8 140.97)
		)
		(stroke
			(width 0)
			(type default)
		)
	)
	(bus
		(pts
			(xy 149.86 132.08) (xy 149.86 134.62)
		)
		(stroke
			(width 0)
			(type default)
		)
	)
	(bus
		(pts
			(xy 149.86 73.66) (xy 148.59 72.39)
		)
		(stroke
			(width 0)
			(type default)
		)
	)
	(bus
		(pts
			(xy 124.46 81.28) (xy 124.46 82.55)
		)
		(stroke
			(width 0)
			(type default)
		)
	)
	(bus
		(pts
			(xy 124.46 85.09) (xy 124.46 87.63)
		)
		(stroke
			(width 0)
			(type default)
		)
	)
	(wire
		(pts
			(xy 127 130.81) (xy 177.8 130.81)
		)
		(stroke
			(width 0)
			(type default)
		)
	)
	(wire
		(pts
			(xy 151.13 120.65) (xy 177.8 120.65)
		)
		(stroke
			(width 0)
			(type default)
		)
	)
	(wire
		(pts
			(xy 58.42 247.65) (xy 58.42 248.92)
		)
		(stroke
			(width 0)
			(type default)
		)
	)
	(bus
		(pts
			(xy 124.46 102.87) (xy 124.46 105.41)
		)
		(stroke
			(width 0)
			(type default)
		)
	)
	(wire
		(pts
			(xy 151.13 128.27) (xy 177.8 128.27)
		)
		(stroke
			(width 0)
			(type default)
		)
	)
	(bus
		(pts
			(xy 149.86 116.84) (xy 149.86 119.38)
		)
		(stroke
			(width 0)
			(type default)
		)
	)
	(bus
		(pts
			(xy 124.46 92.71) (xy 124.46 95.25)
		)
		(stroke
			(width 0)
			(type default)
		)
	)
	(wire
		(pts
			(xy 151.13 77.47) (xy 177.8 77.47)
		)
		(stroke
			(width 0)
			(type default)
		)
	)
	(bus
		(pts
			(xy 149.86 134.62) (xy 149.86 142.24)
		)
		(stroke
			(width 0)
			(type default)
		)
	)
	(wire
		(pts
			(xy 49.53 248.92) (xy 58.42 248.92)
		)
		(stroke
			(width 0)
			(type default)
		)
	)
	(bus
		(pts
			(xy 124.46 105.41) (xy 124.46 120.65)
		)
		(stroke
			(width 0)
			(type default)
		)
	)
	(bus
		(pts
			(xy 121.92 80.01) (xy 123.19 80.01)
		)
		(stroke
			(width 0)
			(type default)
		)
	)
	(bus
		(pts
			(xy 124.46 120.65) (xy 124.46 128.27)
		)
		(stroke
			(width 0)
			(type default)
		)
	)
	(wire
		(pts
			(xy 49.53 240.03) (xy 49.53 241.3)
		)
		(stroke
			(width 0)
			(type default)
		)
	)
	(wire
		(pts
			(xy 127 95.25) (xy 177.8 95.25)
		)
		(stroke
			(width 0)
			(type default)
		)
	)
	(wire
		(pts
			(xy 127 105.41) (xy 177.8 105.41)
		)
		(stroke
			(width 0)
			(type default)
		)
	)
	(bus
		(pts
			(xy 124.46 135.89) (xy 124.46 138.43)
		)
		(stroke
			(width 0)
			(type default)
		)
	)
	(wire
		(pts
			(xy 58.42 241.3) (xy 58.42 242.57)
		)
		(stroke
			(width 0)
			(type default)
		)
	)
	(bus
		(pts
			(xy 149.86 114.3) (xy 149.86 116.84)
		)
		(stroke
			(width 0)
			(type default)
		)
	)
	(wire
		(pts
			(xy 151.13 110.49) (xy 177.8 110.49)
		)
		(stroke
			(width 0)
			(type default)
		)
	)
	(bus
		(pts
			(xy 149.86 119.38) (xy 149.86 124.46)
		)
		(stroke
			(width 0)
			(type default)
		)
	)
	(wire
		(pts
			(xy 127 85.09) (xy 177.8 85.09)
		)
		(stroke
			(width 0)
			(type default)
		)
	)
	(bus
		(pts
			(xy 149.86 76.2) (xy 149.86 78.74)
		)
		(stroke
			(width 0)
			(type default)
		)
	)
	(wire
		(pts
			(xy 151.13 80.01) (xy 177.8 80.01)
		)
		(stroke
			(width 0)
			(type default)
		)
	)
	(wire
		(pts
			(xy 58.42 245.11) (xy 58.42 242.57)
		)
		(stroke
			(width 0)
			(type default)
		)
	)
	(bus
		(pts
			(xy 149.86 81.28) (xy 149.86 109.22)
		)
		(stroke
			(width 0)
			(type default)
		)
	)
	(wire
		(pts
			(xy 151.13 115.57) (xy 177.8 115.57)
		)
		(stroke
			(width 0)
			(type default)
		)
	)
	(bus
		(pts
			(xy 124.46 100.33) (xy 124.46 102.87)
		)
		(stroke
			(width 0)
			(type default)
		)
	)
	(wire
		(pts
			(xy 127 90.17) (xy 177.8 90.17)
		)
		(stroke
			(width 0)
			(type default)
		)
	)
	(bus
		(pts
			(xy 149.86 124.46) (xy 149.86 127)
		)
		(stroke
			(width 0)
			(type default)
		)
	)
	(wire
		(pts
			(xy 127 87.63) (xy 177.8 87.63)
		)
		(stroke
			(width 0)
			(type default)
		)
	)
	(wire
		(pts
			(xy 127 100.33) (xy 177.8 100.33)
		)
		(stroke
			(width 0)
			(type default)
		)
	)
	(wire
		(pts
			(xy 151.13 133.35) (xy 177.8 133.35)
		)
		(stroke
			(width 0)
			(type default)
		)
	)
	(wire
		(pts
			(xy 49.53 248.92) (xy 49.53 250.19)
		)
		(stroke
			(width 0)
			(type default)
		)
	)
	(wire
		(pts
			(xy 49.53 247.65) (xy 49.53 248.92)
		)
		(stroke
			(width 0)
			(type default)
		)
	)
	(bus
		(pts
			(xy 149.86 73.66) (xy 149.86 76.2)
		)
		(stroke
			(width 0)
			(type default)
		)
	)
	(wire
		(pts
			(xy 279.4 133.35) (xy 269.24 133.35)
		)
		(stroke
			(width 0)
			(type default)
		)
	)
	(bus
		(pts
			(xy 149.86 127) (xy 149.86 132.08)
		)
		(stroke
			(width 0)
			(type default)
		)
	)
	(bus
		(pts
			(xy 124.46 128.27) (xy 124.46 135.89)
		)
		(stroke
			(width 0)
			(type default)
		)
	)
	(wire
		(pts
			(xy 127 102.87) (xy 177.8 102.87)
		)
		(stroke
			(width 0)
			(type default)
		)
	)
	(wire
		(pts
			(xy 58.42 242.57) (xy 59.69 242.57)
		)
		(stroke
			(width 0)
			(type default)
		)
	)
	(wire
		(pts
			(xy 78.74 242.57) (xy 91.44 242.57)
		)
		(stroke
			(width 0)
			(type default)
		)
	)
	(wire
		(pts
			(xy 59.69 247.65) (xy 58.42 247.65)
		)
		(stroke
			(width 0)
			(type default)
		)
	)
	(wire
		(pts
			(xy 151.13 143.51) (xy 177.8 143.51)
		)
		(stroke
			(width 0)
			(type default)
		)
	)
	(wire
		(pts
			(xy 151.13 113.03) (xy 177.8 113.03)
		)
		(stroke
			(width 0)
			(type default)
		)
	)
	(bus
		(pts
			(xy 124.46 97.79) (xy 124.46 100.33)
		)
		(stroke
			(width 0)
			(type default)
		)
	)
	(bus
		(pts
			(xy 124.46 87.63) (xy 124.46 92.71)
		)
		(stroke
			(width 0)
			(type default)
		)
	)
	(wire
		(pts
			(xy 59.69 245.11) (xy 58.42 245.11)
		)
		(stroke
			(width 0)
			(type default)
		)
	)
	(wire
		(pts
			(xy 151.13 135.89) (xy 177.8 135.89)
		)
		(stroke
			(width 0)
			(type default)
		)
	)
	(bus
		(pts
			(xy 149.86 109.22) (xy 149.86 111.76)
		)
		(stroke
			(width 0)
			(type default)
		)
	)
	(bus
		(pts
			(xy 147.32 72.39) (xy 148.59 72.39)
		)
		(stroke
			(width 0)
			(type default)
		)
	)
	(bus
		(pts
			(xy 149.86 111.76) (xy 149.86 114.3)
		)
		(stroke
			(width 0)
			(type default)
		)
	)
	(wire
		(pts
			(xy 127 97.79) (xy 177.8 97.79)
		)
		(stroke
			(width 0)
			(type default)
		)
	)
	(wire
		(pts
			(xy 49.53 241.3) (xy 49.53 242.57)
		)
		(stroke
			(width 0)
			(type default)
		)
	)
	(bus
		(pts
			(xy 149.86 78.74) (xy 149.86 81.28)
		)
		(stroke
			(width 0)
			(type default)
		)
	)
	(wire
		(pts
			(xy 127 123.19) (xy 177.8 123.19)
		)
		(stroke
			(width 0)
			(type default)
		)
	)
	(wire
		(pts
			(xy 49.53 241.3) (xy 58.42 241.3)
		)
		(stroke
			(width 0)
			(type default)
		)
	)
	(bus
		(pts
			(xy 124.46 82.55) (xy 124.46 85.09)
		)
		(stroke
			(width 0)
			(type default)
		)
	)
	(label "Crosslink_B1.D0"
		(at 153.67 118.11 0)
		(effects
			(font
				(size 1.27 1.27)
			)
			(justify left bottom)
		)
	)
	(label "PF_CLK"
		(at 91.44 242.57 180)
		(effects
			(font
				(size 1.27 1.27)
			)
			(justify right bottom)
		)
	)
	(label "Crosslink_B1.HSYNC"
		(at 153.035 80.01 0)
		(effects
			(font
				(size 1.27 1.27)
			)
			(justify left bottom)
		)
	)
	(label "Crosslink_B2.D2"
		(at 127 105.41 0)
		(effects
			(font
				(size 1.27 1.27)
			)
			(justify left bottom)
		)
	)
	(label "Crosslink_B1.D6"
		(at 153.67 110.49 0)
		(effects
			(font
				(size 1.27 1.27)
			)
			(justify left bottom)
		)
	)
	(label "Crosslink_B2.VSYNC"
		(at 128.27 85.09 0)
		(effects
			(font
				(size 1.27 1.27)
			)
			(justify left bottom)
		)
	)
	(label "Crosslink_B2.HSYNC"
		(at 128.27 87.63 0)
		(effects
			(font
				(size 1.27 1.27)
			)
			(justify left bottom)
		)
	)
	(label "Crosslink_B2.D1"
		(at 127 107.95 0)
		(effects
			(font
				(size 1.27 1.27)
			)
			(justify left bottom)
		)
	)
	(label "Crosslink_B1.D5"
		(at 153.67 143.51 0)
		(effects
			(font
				(size 1.27 1.27)
			)
			(justify left bottom)
		)
	)
	(label "Crosslink_B2.D7"
		(at 127 130.81 0)
		(effects
			(font
				(size 1.27 1.27)
			)
			(justify left bottom)
		)
	)
	(label "Crosslink_B2.D6"
		(at 127 140.97 0)
		(effects
			(font
				(size 1.27 1.27)
			)
			(justify left bottom)
		)
	)
	(label "Crosslink_B2.PCLK"
		(at 128.27 90.17 0)
		(effects
			(font
				(size 1.27 1.27)
			)
			(justify left bottom)
		)
	)
	(label "Crosslink_B1.D3"
		(at 153.67 115.57 0)
		(effects
			(font
				(size 1.27 1.27)
			)
			(justify left bottom)
		)
	)
	(label "Crosslink_B1.D7"
		(at 153.67 125.73 0)
		(effects
			(font
				(size 1.27 1.27)
			)
			(justify left bottom)
		)
	)
	(label "Crosslink_B2.D0"
		(at 127 102.87 0)
		(effects
			(font
				(size 1.27 1.27)
			)
			(justify left bottom)
		)
	)
	(label "Crosslink_B1.PCLK"
		(at 153.035 82.55 0)
		(effects
			(font
				(size 1.27 1.27)
			)
			(justify left bottom)
		)
	)
	(label "Crosslink_B1.D9"
		(at 153.67 135.89 0)
		(effects
			(font
				(size 1.27 1.27)
			)
			(justify left bottom)
		)
	)
	(label "Crosslink_B1.D2"
		(at 153.67 113.03 0)
		(effects
			(font
				(size 1.27 1.27)
			)
			(justify left bottom)
		)
	)
	(label "Crosslink_B1.D4"
		(at 153.67 128.27 0)
		(effects
			(font
				(size 1.27 1.27)
			)
			(justify left bottom)
		)
	)
	(label "Crosslink_B2.D5"
		(at 127 95.25 0)
		(effects
			(font
				(size 1.27 1.27)
			)
			(justify left bottom)
		)
	)
	(label "Crosslink_B2.D9"
		(at 127.635 138.43 0)
		(effects
			(font
				(size 1.27 1.27)
			)
			(justify left bottom)
		)
	)
	(label "Crosslink_B2.D4"
		(at 127 97.79 0)
		(effects
			(font
				(size 1.27 1.27)
			)
			(justify left bottom)
		)
	)
	(label "Crosslink_B2.D3"
		(at 127 100.33 0)
		(effects
			(font
				(size 1.27 1.27)
			)
			(justify left bottom)
		)
	)
	(label "Crosslink_B2.D8"
		(at 127 123.19 0)
		(effects
			(font
				(size 1.27 1.27)
			)
			(justify left bottom)
		)
	)
	(label "Crosslink_B1.D1"
		(at 153.67 120.65 0)
		(effects
			(font
				(size 1.27 1.27)
			)
			(justify left bottom)
		)
	)
	(label "Crosslink_B1.VSYNC"
		(at 153.035 77.47 0)
		(effects
			(font
				(size 1.27 1.27)
			)
			(justify left bottom)
		)
	)
	(label "PF_CLK"
		(at 279.4 133.35 180)
		(effects
			(font
				(size 1.27 1.27)
			)
			(justify right bottom)
		)
	)
	(label "Crosslink_B1.D8"
		(at 153.67 133.35 0)
		(effects
			(font
				(size 1.27 1.27)
			)
			(justify left bottom)
		)
	)
	(hierarchical_label "Crosslink_B1{CPI}"
		(shape input)
		(at 147.32 72.39 180)
		(effects
			(font
				(size 1.27 1.27)
			)
			(justify right)
		)
	)
	(hierarchical_label "Crosslink_B2{CPI}"
		(shape input)
		(at 121.92 80.01 180)
		(effects
			(font
				(size 1.27 1.27)
			)
			(justify right)
		)
	)
	(symbol
		(lib_id "antmicroFPGAChips:MPFS250T-FCVG484E")
		(at 177.8 77.47 0)
		(unit 1)
		(exclude_from_sim no)
		(in_bom yes)
		(on_board yes)
		(dnp no)
		(fields_autoplaced yes)
		(property "Reference" "U1"
			(at 223.52 67.31 0)
			(effects
				(font
					(size 1.27 1.27)
					(thickness 0.15)
				)
			)
		)
		(property "Value" "MPFS250T-FCVG484"
			(at 283.21 82.55 0)
			(effects
				(font
					(size 1.27 1.27)
					(thickness 0.15)
				)
				(justify left bottom)
				(hide yes)
			)
		)
		(property "Footprint" "antmicro-footprints:BGA-484_19x19mm_Layout22x22_P0.8mm_FCVG484"
			(at 283.21 85.09 0)
			(effects
				(font
					(size 1.27 1.27)
					(thickness 0.15)
				)
				(justify left bottom)
				(hide yes)
			)
		)
		(property "Datasheet" "https://ww1.microchip.com/downloads/aemDocuments/documents/FPGA/ProductDocuments/DataSheets/PolarFire-SoC-Datasheet-DS00004248.pdf"
			(at 283.21 87.63 0)
			(effects
				(font
					(size 1.27 1.27)
					(thickness 0.15)
				)
				(justify left bottom)
				(hide yes)
			)
		)
		(property "Description" "RISC-V System On Chip (SOC) IC PolarFire® FPGA - 254K Logic Modules 484-FCBGA (19x19)"
			(at 283.21 97.79 0)
			(effects
				(font
					(size 1.27 1.27)
				)
				(justify left bottom)
				(hide yes)
			)
		)
		(property "MPN" "MPFS250T-FCVG484E"
			(at 223.52 69.85 0)
			(effects
				(font
					(size 1.27 1.27)
					(thickness 0.15)
				)
			)
		)
		(property "Manufacturer" "Microchip Technology"
			(at 283.21 90.17 0)
			(effects
				(font
					(size 1.27 1.27)
					(thickness 0.15)
				)
				(justify left bottom)
				(hide yes)
			)
		)
		(property "VSD_class" "MPFS250T"
			(at 281.94 95.25 0)
			(effects
				(font
					(size 1.27 1.27)
					(thickness 0.15)
				)
				(justify left bottom)
				(hide yes)
			)
		)
		(property "Author" "Antmicro"
			(at 283.21 92.71 0)
			(effects
				(font
					(size 1.27 1.27)
					(thickness 0.15)
				)
				(justify left bottom)
				(hide yes)
			)
		)
		(property "License" "Apache-2.0"
			(at 283.21 95.25 0)
			(effects
				(font
					(size 1.27 1.27)
					(thickness 0.15)
				)
				(justify left bottom)
				(hide yes)
			)
		)
		(pin "AA12"
		)
		(pin "AA13"
		)
		(pin "AA15"
		)
		(pin "AA16"
		)
		(pin "AA17"
		)
		(pin "AA18"
		)
		(pin "AA20"
		)
		(pin "AA21"
		)
		(pin "AA22"
		)
		(pin "AB12"
		)
		(pin "AB13"
		)
		(pin "AB14"
		)
		(pin "AB15"
		)
		(pin "AB17"
		)
		(pin "AB18"
		)
		(pin "AB19"
		)
		(pin "AB20"
		)
		(pin "AB21"
		)
		(pin "R12"
		)
		(pin "R14"
		)
		(pin "R15"
		)
		(pin "R16"
		)
		(pin "T12"
		)
		(pin "T13"
		)
		(pin "T15"
		)
		(pin "T16"
		)
		(pin "T17"
		)
		(pin "U12"
		)
		(pin "U13"
		)
		(pin "U14"
		)
		(pin "U15"
		)
		(pin "U17"
		)
		(pin "U18"
		)
		(pin "U19"
		)
		(pin "V12"
		)
		(pin "V14"
		)
		(pin "V15"
		)
		(pin "V16"
		)
		(pin "V17"
		)
		(pin "V19"
		)
		(pin "V20"
		)
		(pin "V21"
		)
		(pin "V22"
		)
		(pin "W12"
		)
		(pin "W13"
		)
		(pin "W14"
		)
		(pin "W16"
		)
		(pin "W17"
		)
		(pin "W18"
		)
		(pin "W19"
		)
		(pin "W21"
		)
		(pin "W22"
		)
		(pin "Y13"
		)
		(pin "Y14"
		)
		(pin "Y15"
		)
		(pin "Y16"
		)
		(pin "Y18"
		)
		(pin "Y19"
		)
		(pin "Y20"
		)
		(pin "Y21"
		)
		(pin "A10"
		)
		(pin "A11"
		)
		(pin "A12"
		)
		(pin "A13"
		)
		(pin "A15"
		)
		(pin "A16"
		)
		(pin "A17"
		)
		(pin "A18"
		)
		(pin "A20"
		)
		(pin "A21"
		)
		(pin "A5"
		)
		(pin "A6"
		)
		(pin "A7"
		)
		(pin "A8"
		)
		(pin "B10"
		)
		(pin "B12"
		)
		(pin "B13"
		)
		(pin "B14"
		)
		(pin "B15"
		)
		(pin "B17"
		)
		(pin "B18"
		)
		(pin "B19"
		)
		(pin "B20"
		)
		(pin "B21"
		)
		(pin "B22"
		)
		(pin "B4"
		)
		(pin "B5"
		)
		(pin "B7"
		)
		(pin "B8"
		)
		(pin "B9"
		)
		(pin "C10"
		)
		(pin "C11"
		)
		(pin "C12"
		)
		(pin "C14"
		)
		(pin "C15"
		)
		(pin "C16"
		)
		(pin "C17"
		)
		(pin "C19"
		)
		(pin "C20"
		)
		(pin "C22"
		)
		(pin "C4"
		)
		(pin "C5"
		)
		(pin "C6"
		)
		(pin "C7"
		)
		(pin "C9"
		)
		(pin "D11"
		)
		(pin "D12"
		)
		(pin "D13"
		)
		(pin "D14"
		)
		(pin "D16"
		)
		(pin "D17"
		)
		(pin "D18"
		)
		(pin "D19"
		)
		(pin "D20"
		)
		(pin "D21"
		)
		(pin "D22"
		)
		(pin "D6"
		)
		(pin "D7"
		)
		(pin "D8"
		)
		(pin "D9"
		)
		(pin "E10"
		)
		(pin "E11"
		)
		(pin "E13"
		)
		(pin "E14"
		)
		(pin "E15"
		)
		(pin "E16"
		)
		(pin "E18"
		)
		(pin "E19"
		)
		(pin "F10"
		)
		(pin "F11"
		)
		(pin "F12"
		)
		(pin "F13"
		)
		(pin "F15"
		)
		(pin "F16"
		)
		(pin "F17"
		)
		(pin "G12"
		)
		(pin "G13"
		)
		(pin "G14"
		)
		(pin "G15"
		)
		(pin "G17"
		)
		(pin "H12"
		)
		(pin "H13"
		)
		(pin "H15"
		)
		(pin "H17"
		)
		(pin "A2"
		)
		(pin "A3"
		)
		(pin "B1"
		)
		(pin "B2"
		)
		(pin "B3"
		)
		(pin "C1"
		)
		(pin "C2"
		)
		(pin "D1"
		)
		(pin "D2"
		)
		(pin "D3"
		)
		(pin "D4"
		)
		(pin "E1"
		)
		(pin "E3"
		)
		(pin "E4"
		)
		(pin "E5"
		)
		(pin "F1"
		)
		(pin "F2"
		)
		(pin "F3"
		)
		(pin "F5"
		)
		(pin "F6"
		)
		(pin "G2"
		)
		(pin "G3"
		)
		(pin "G4"
		)
		(pin "G5"
		)
		(pin "E6"
		)
		(pin "E8"
		)
		(pin "E9"
		)
		(pin "F7"
		)
		(pin "F8"
		)
		(pin "G10"
		)
		(pin "G7"
		)
		(pin "G8"
		)
		(pin "G9"
		)
		(pin "H10"
		)
		(pin "H11"
		)
		(pin "H7"
		)
		(pin "H9"
		)
		(pin "H1"
		)
		(pin "H2"
		)
		(pin "H4"
		)
		(pin "H5"
		)
		(pin "H6"
		)
		(pin "J1"
		)
		(pin "J2"
		)
		(pin "J3"
		)
		(pin "J4"
		)
		(pin "J6"
		)
		(pin "J7"
		)
		(pin "K3"
		)
		(pin "K4"
		)
		(pin "K5"
		)
		(pin "K6"
		)
		(pin "K7"
		)
		(pin "L5"
		)
		(pin "L6"
		)
		(pin "L7"
		)
		(pin "L8"
		)
		(pin "M7"
		)
		(pin "N6"
		)
		(pin "N7"
		)
		(pin "N8"
		)
		(pin "AA1"
		)
		(pin "AA10"
		)
		(pin "AA11"
		)
		(pin "AA2"
		)
		(pin "AA3"
		)
		(pin "AA5"
		)
		(pin "AA6"
		)
		(pin "AA7"
		)
		(pin "AA8"
		)
		(pin "AB10"
		)
		(pin "AB2"
		)
		(pin "AB3"
		)
		(pin "AB4"
		)
		(pin "AB5"
		)
		(pin "AB7"
		)
		(pin "AB8"
		)
		(pin "AB9"
		)
		(pin "K1"
		)
		(pin "L1"
		)
		(pin "L2"
		)
		(pin "L3"
		)
		(pin "M2"
		)
		(pin "M3"
		)
		(pin "M4"
		)
		(pin "M5"
		)
		(pin "N1"
		)
		(pin "N2"
		)
		(pin "N4"
		)
		(pin "N5"
		)
		(pin "P1"
		)
		(pin "P2"
		)
		(pin "P3"
		)
		(pin "P4"
		)
		(pin "P6"
		)
		(pin "P7"
		)
		(pin "P8"
		)
		(pin "R1"
		)
		(pin "R10"
		)
		(pin "R11"
		)
		(pin "R3"
		)
		(pin "R4"
		)
		(pin "R5"
		)
		(pin "R6"
		)
		(pin "R8"
		)
		(pin "T1"
		)
		(pin "T10"
		)
		(pin "T11"
		)
		(pin "T2"
		)
		(pin "T3"
		)
		(pin "T5"
		)
		(pin "T6"
		)
		(pin "T7"
		)
		(pin "T8"
		)
		(pin "U10"
		)
		(pin "U2"
		)
		(pin "U3"
		)
		(pin "U4"
		)
		(pin "U5"
		)
		(pin "U7"
		)
		(pin "U8"
		)
		(pin "U9"
		)
		(pin "V1"
		)
		(pin "V10"
		)
		(pin "V11"
		)
		(pin "V2"
		)
		(pin "V4"
		)
		(pin "V5"
		)
		(pin "V6"
		)
		(pin "V7"
		)
		(pin "V9"
		)
		(pin "W1"
		)
		(pin "W11"
		)
		(pin "W2"
		)
		(pin "W3"
		)
		(pin "W4"
		)
		(pin "W6"
		)
		(pin "W7"
		)
		(pin "W8"
		)
		(pin "W9"
		)
		(pin "Y1"
		)
		(pin "Y10"
		)
		(pin "Y11"
		)
		(pin "Y3"
		)
		(pin "Y4"
		)
		(pin "Y5"
		)
		(pin "Y6"
		)
		(pin "Y8"
		)
		(pin "Y9"
		)
		(pin "F21"
		)
		(pin "F22"
		)
		(pin "G19"
		)
		(pin "G20"
		)
		(pin "H21"
		)
		(pin "H22"
		)
		(pin "J19"
		)
		(pin "J20"
		)
		(pin "K21"
		)
		(pin "K22"
		)
		(pin "L19"
		)
		(pin "L20"
		)
		(pin "M21"
		)
		(pin "M22"
		)
		(pin "N19"
		)
		(pin "N20"
		)
		(pin "P21"
		)
		(pin "P22"
		)
		(pin "R19"
		)
		(pin "R20"
		)
		(pin "T21"
		)
		(pin "T22"
		)
		(pin "A1"
		)
		(pin "A14"
		)
		(pin "A19"
		)
		(pin "A22"
		)
		(pin "A4"
		)
		(pin "A9"
		)
		(pin "AA14"
		)
		(pin "AA19"
		)
		(pin "AA4"
		)
		(pin "AA9"
		)
		(pin "AB1"
		)
		(pin "AB11"
		)
		(pin "AB16"
		)
		(pin "AB22"
		)
		(pin "AB6"
		)
		(pin "B11"
		)
		(pin "B16"
		)
		(pin "B6"
		)
		(pin "C13"
		)
		(pin "C18"
		)
		(pin "C21"
		)
		(pin "C3"
		)
		(pin "C8"
		)
		(pin "D10"
		)
		(pin "D15"
		)
		(pin "D5"
		)
		(pin "E12"
		)
		(pin "E17"
		)
		(pin "E2"
		)
		(pin "E20"
		)
		(pin "E21"
		)
		(pin "E22"
		)
		(pin "E7"
		)
		(pin "F14"
		)
		(pin "F18"
		)
		(pin "F19"
		)
		(pin "F20"
		)
		(pin "F4"
		)
		(pin "F9"
		)
		(pin "G1"
		)
		(pin "G11"
		)
		(pin "G16"
		)
		(pin "G18"
		)
		(pin "G21"
		)
		(pin "G22"
		)
		(pin "G6"
		)
		(pin "H14"
		)
		(pin "H16"
		)
		(pin "H18"
		)
		(pin "H19"
		)
		(pin "H20"
		)
		(pin "H3"
		)
		(pin "H8"
		)
		(pin "J10"
		)
		(pin "J11"
		)
		(pin "J12"
		)
		(pin "J13"
		)
		(pin "J14"
		)
		(pin "J15"
		)
		(pin "J16"
		)
		(pin "J17"
		)
		(pin "J18"
		)
		(pin "J21"
		)
		(pin "J22"
		)
		(pin "J5"
		)
		(pin "J8"
		)
		(pin "J9"
		)
		(pin "K10"
		)
		(pin "K11"
		)
		(pin "K12"
		)
		(pin "K13"
		)
		(pin "K14"
		)
		(pin "K15"
		)
		(pin "K16"
		)
		(pin "K17"
		)
		(pin "K18"
		)
		(pin "K19"
		)
		(pin "K2"
		)
		(pin "K20"
		)
		(pin "K8"
		)
		(pin "K9"
		)
		(pin "L10"
		)
		(pin "L11"
		)
		(pin "L12"
		)
		(pin "L13"
		)
		(pin "L14"
		)
		(pin "L15"
		)
		(pin "L16"
		)
		(pin "L17"
		)
		(pin "L18"
		)
		(pin "L21"
		)
		(pin "L22"
		)
		(pin "L4"
		)
		(pin "L9"
		)
		(pin "M1"
		)
		(pin "M10"
		)
		(pin "M11"
		)
		(pin "M12"
		)
		(pin "M13"
		)
		(pin "M14"
		)
		(pin "M15"
		)
		(pin "M16"
		)
		(pin "M17"
		)
		(pin "M18"
		)
		(pin "M19"
		)
		(pin "M20"
		)
		(pin "M6"
		)
		(pin "M8"
		)
		(pin "M9"
		)
		(pin "N10"
		)
		(pin "N11"
		)
		(pin "N12"
		)
		(pin "N13"
		)
		(pin "N14"
		)
		(pin "N15"
		)
		(pin "N16"
		)
		(pin "N17"
		)
		(pin "N18"
		)
		(pin "N21"
		)
		(pin "N22"
		)
		(pin "N3"
		)
		(pin "N9"
		)
		(pin "P10"
		)
		(pin "P11"
		)
		(pin "P12"
		)
		(pin "P13"
		)
		(pin "P14"
		)
		(pin "P15"
		)
		(pin "P16"
		)
		(pin "P17"
		)
		(pin "P18"
		)
		(pin "P19"
		)
		(pin "P20"
		)
		(pin "P5"
		)
		(pin "P9"
		)
		(pin "R13"
		)
		(pin "R17"
		)
		(pin "R18"
		)
		(pin "R2"
		)
		(pin "R21"
		)
		(pin "R22"
		)
		(pin "R7"
		)
		(pin "R9"
		)
		(pin "T14"
		)
		(pin "T18"
		)
		(pin "T19"
		)
		(pin "T20"
		)
		(pin "T4"
		)
		(pin "T9"
		)
		(pin "U1"
		)
		(pin "U11"
		)
		(pin "U16"
		)
		(pin "U20"
		)
		(pin "U21"
		)
		(pin "U22"
		)
		(pin "U6"
		)
		(pin "V13"
		)
		(pin "V18"
		)
		(pin "V3"
		)
		(pin "V8"
		)
		(pin "W10"
		)
		(pin "W15"
		)
		(pin "W20"
		)
		(pin "W5"
		)
		(pin "Y12"
		)
		(pin "Y17"
		)
		(pin "Y2"
		)
		(pin "Y22"
		)
		(pin "Y7"
		)
		(instances
			(project "polarfire-som"
				(path ""
					(reference "U1")
					(unit 1)
				)
			)
		)
	)
	(symbol
		(lib_id "antmicropower:GND")
		(at 49.53 250.19 0)
		(unit 1)
		(exclude_from_sim no)
		(in_bom yes)
		(on_board yes)
		(dnp no)
		(property "Reference" "#PWR0165"
			(at 58.42 252.73 0)
			(effects
				(font
					(size 1.27 1.27)
					(thickness 0.15)
				)
				(justify left bottom)
				(hide yes)
			)
		)
		(property "Value" "GND"
			(at 49.53 254 0)
			(effects
				(font
					(size 1.27 1.27)
					(thickness 0.15)
				)
			)
		)
		(property "Footprint" ""
			(at 58.42 257.81 0)
			(effects
				(font
					(size 1.27 1.27)
					(thickness 0.15)
				)
				(justify left bottom)
				(hide yes)
			)
		)
		(property "Datasheet" ""
			(at 58.42 262.89 0)
			(effects
				(font
					(size 1.27 1.27)
					(thickness 0.15)
				)
				(justify left bottom)
				(hide yes)
			)
		)
		(property "Description" ""
			(at 49.53 250.19 0)
			(effects
				(font
					(size 1.27 1.27)
				)
				(hide yes)
			)
		)
		(property "Author" "Antmicro"
			(at 58.42 257.81 0)
			(effects
				(font
					(size 1.27 1.27)
					(thickness 0.15)
				)
				(justify left bottom)
				(hide yes)
			)
		)
		(property "License" "Apache-2.0"
			(at 58.42 260.35 0)
			(effects
				(font
					(size 1.27 1.27)
					(thickness 0.15)
				)
				(justify left bottom)
				(hide yes)
			)
		)
		(pin "1"
		)
		(instances
			(project "polarfire-som"
				(path ""
					(reference "#PWR0165")
					(unit 1)
				)
			)
		)
	)
	(symbol
		(lib_id "antmicroCapacitors0402:C_100n_0402")
		(at 49.53 247.65 90)
		(unit 1)
		(exclude_from_sim no)
		(in_bom yes)
		(on_board yes)
		(dnp no)
		(property "Reference" "C2"
			(at 52.07 243.84 90)
			(effects
				(font
					(size 1.27 1.27)
					(thickness 0.15)
				)
				(justify right)
			)
		)
		(property "Value" "C_100n_0402"
			(at 59.69 227.33 0)
			(effects
				(font
					(size 1.27 1.27)
					(thickness 0.15)
				)
				(justify left bottom)
				(hide yes)
			)
		)
		(property "Footprint" "antmicro-footprints:C_0402_1005Metric"
			(at 62.23 227.33 0)
			(effects
				(font
					(size 1.27 1.27)
					(thickness 0.15)
				)
				(justify left bottom)
				(hide yes)
			)
		)
		(property "Datasheet" "https://www.murata.com/products/productdetail?partno=GRM155R61H104KE14%23"
			(at 64.77 227.33 0)
			(effects
				(font
					(size 1.27 1.27)
					(thickness 0.15)
				)
				(justify left bottom)
				(hide yes)
			)
		)
		(property "Description" "SMD Multilayer Ceramic Capacitor, 0.1 µF, 50 V, 0402 [1005 Metric], ± 10%, X5R, GRM Series"
			(at 49.53 247.65 0)
			(effects
				(font
					(size 1.27 1.27)
				)
				(hide yes)
			)
		)
		(property "MPN" "GRM155R61H104KE14D"
			(at 67.31 227.33 0)
			(effects
				(font
					(size 1.27 1.27)
					(thickness 0.15)
				)
				(justify left bottom)
				(hide yes)
			)
		)
		(property "Manufacturer" "Murata"
			(at 69.85 227.33 0)
			(effects
				(font
					(size 1.27 1.27)
					(thickness 0.15)
				)
				(justify left bottom)
				(hide yes)
			)
		)
		(property "License" "Apache-2.0"
			(at 72.39 227.33 0)
			(effects
				(font
					(size 1.27 1.27)
					(thickness 0.15)
				)
				(justify left bottom)
				(hide yes)
			)
		)
		(property "Author" "Antmicro"
			(at 74.93 227.33 0)
			(effects
				(font
					(size 1.27 1.27)
					(thickness 0.15)
				)
				(justify left bottom)
				(hide yes)
			)
		)
		(property "Val" "100n"
			(at 57.15 246.38 90)
			(effects
				(font
					(size 1.27 1.27)
					(thickness 0.15)
				)
				(justify left bottom)
			)
		)
		(property "Voltage" "50V"
			(at 77.47 227.33 0)
			(effects
				(font
					(size 1.27 1.27)
				)
				(justify left bottom)
				(hide yes)
			)
		)
		(property "Dielectric" "X5R"
			(at 80.01 227.33 0)
			(effects
				(font
					(size 1.27 1.27)
				)
				(justify left bottom)
				(hide yes)
			)
		)
		(property "Public" ""
			(at 82.55 227.33 0)
			(effects
				(font
					(size 1.27 1.27)
				)
				(justify left bottom)
				(hide yes)
			)
		)
		(pin "1"
		)
		(pin "2"
		)
		(instances
			(project "polarfire-som"
				(path ""
					(reference "C2")
					(unit 1)
				)
			)
		)
	)
	(symbol
		(lib_id "antmicroOscillators:Oscillator_50MHz_ECS_1612MV")
		(at 59.69 242.57 0)
		(unit 1)
		(exclude_from_sim no)
		(in_bom yes)
		(on_board yes)
		(dnp no)
		(fields_autoplaced yes)
		(property "Reference" "Y5"
			(at 69.215 232.41 0)
			(effects
				(font
					(size 1.27 1.27)
					(thickness 0.15)
				)
			)
		)
		(property "Value" "Oscillator_50MHz_ECS_1612MV"
			(at 86.36 254.635 0)
			(effects
				(font
					(size 1.27 1.27)
					(thickness 0.15)
				)
				(justify left bottom)
				(hide yes)
			)
		)
		(property "Footprint" "antmicro-footprints:Oscillator_SMD_ECS_1612MV_1.6x1.2x0.6mm"
			(at 86.36 257.175 0)
			(effects
				(font
					(size 1.27 1.27)
					(thickness 0.15)
				)
				(justify left bottom)
				(hide yes)
			)
		)
		(property "Datasheet" "https://ecsxtal.com/store/pdf/ECS-1612MV.pdf"
			(at 86.36 259.715 0)
			(effects
				(font
					(size 1.27 1.27)
					(thickness 0.15)
				)
				(justify left bottom)
				(hide yes)
			)
		)
		(property "Description" "50 MHz XO (Standard) CMOS Oscillator 1.6V ~ 3.63V Standby 4-SMD, No Lead"
			(at 59.69 242.57 0)
			(effects
				(font
					(size 1.27 1.27)
				)
				(hide yes)
			)
		)
		(property "MPN" "ECS-1612MV-500-CN-TR"
			(at 69.215 234.95 0)
			(effects
				(font
					(size 1.27 1.27)
					(thickness 0.15)
				)
			)
		)
		(property "Manufacturer" "ECS Inc. International"
			(at 86.36 262.255 0)
			(effects
				(font
					(size 1.27 1.27)
					(thickness 0.15)
				)
				(justify left bottom)
				(hide yes)
			)
		)
		(property "Val" "50 MHz"
			(at 69.215 237.49 0)
			(effects
				(font
					(size 1.27 1.27)
					(thickness 0.15)
				)
			)
		)
		(property "Author" "Antmicro"
			(at 86.36 264.795 0)
			(effects
				(font
					(size 1.27 1.27)
					(thickness 0.15)
				)
				(justify left bottom)
				(hide yes)
			)
		)
		(property "License" "Apache-2.0"
			(at 86.36 267.335 0)
			(effects
				(font
					(size 1.27 1.27)
					(thickness 0.15)
				)
				(justify left bottom)
				(hide yes)
			)
		)
		(property "Public" ""
			(at 91.44 266.7 0)
			(effects
				(font
					(size 1.27 1.27)
				)
				(justify left bottom)
				(hide yes)
			)
		)
		(pin "4"
		)
		(pin "1"
		)
		(pin "3"
		)
		(pin "2"
		)
		(instances
			(project "polarfire-som"
				(path ""
					(reference "Y5")
					(unit 1)
				)
			)
		)
	)
	(symbol
		(lib_id "antmicropower:+1V8")
		(at 49.53 240.03 0)
		(unit 1)
		(exclude_from_sim no)
		(in_bom yes)
		(on_board yes)
		(dnp no)
		(property "Reference" "#PWR0152"
			(at 64.77 242.57 0)
			(effects
				(font
					(size 1.27 1.27)
					(thickness 0.15)
				)
				(justify left bottom)
				(hide yes)
			)
		)
		(property "Value" "+1V8"
			(at 49.53 236.22 0)
			(effects
				(font
					(size 1.27 1.27)
					(thickness 0.15)
				)
			)
		)
		(property "Footprint" ""
			(at 64.77 247.65 0)
			(effects
				(font
					(size 1.27 1.27)
					(thickness 0.15)
				)
				(justify left bottom)
				(hide yes)
			)
		)
		(property "Datasheet" ""
			(at 64.77 250.19 0)
			(effects
				(font
					(size 1.27 1.27)
					(thickness 0.15)
				)
				(justify left bottom)
				(hide yes)
			)
		)
		(property "Description" ""
			(at 49.53 240.03 0)
			(effects
				(font
					(size 1.27 1.27)
				)
				(hide yes)
			)
		)
		(property "Author" "Antmicro"
			(at 64.77 247.65 0)
			(effects
				(font
					(size 1.27 1.27)
					(thickness 0.15)
				)
				(justify left bottom)
				(hide yes)
			)
		)
		(property "License" "Apache-2.0"
			(at 64.77 250.19 0)
			(effects
				(font
					(size 1.27 1.27)
					(thickness 0.15)
				)
				(justify left bottom)
				(hide yes)
			)
		)
		(pin "1"
		)
		(instances
			(project "polarfire-som"
				(path ""
					(reference "#PWR0152")
					(unit 1)
				)
			)
		)
	)
)
